# T6G (Grand Teton) — schematic netlist excerpt (pin names and nets, part order shuffled) for the footprints in the layout excerpt that follows; sources: Cadence DE-HDL packaged netlist, KiCad conversion of 04192023_DAF0TMB3IC0_F0TG_MB_C_brd_V02_OCP.brd

PR336  Q_RES  0 5% EMPTY  pkg 0402LF  page 211 : A = PVDDCR_CPU0_P1_PVCC ; B = P3V3_AUX
R496  Q_RES  10K 1% EMPTY  pkg 0402LF  page 188 : A = P3V3_AUX ; B = SW_P3V3_EN
R6192  Q_RES  0 5% CHIP  pkg 0201LF  page 180 : A = USB2_CPU0_P0_DP ; B = USB2_CPU0_P0_R2_DP

(kicad_pcb
	(version 20260206)
	(generator "pcbnew")
	(generator_version "10.0")
	(general
		(thickness 1.6)
		(legacy_teardrops no)
	)
	(paper "A4")
	(title_block
		(title "04192023_DAF0TMB3IC0_F0TG_MB_C_brd_V02_OCP.brd")
		(comment 1 "Grand Teton / footprints 595-597 of 8354")
	)
	(layers
		(0 "F.Cu" signal "TOP")
		(4 "In1.Cu" signal "GND")
		(6 "In2.Cu" signal "IN1")
		(8 "In3.Cu" signal "GND1")
		(10 "In4.Cu" signal "IN2")
		(12 "In5.Cu" signal "GND2")
		(14 "In6.Cu" signal "IN3")
		(16 "In7.Cu" signal "GND3")
		(18 "In8.Cu" signal "VCC")
		(20 "In9.Cu" signal "VCC1")
		(22 "In10.Cu" signal "GND4")
		(24 "In11.Cu" signal "IN4")
		(26 "In12.Cu" signal "GND5")
		(28 "In13.Cu" signal "IN5")
		(30 "In14.Cu" signal "GND6")
		(32 "In15.Cu" signal "IN6")
		(34 "In16.Cu" signal "GND7")
		(2 "B.Cu" signal "BOTTOM")
		(9 "F.Adhes" user "F.Adhesive")
		(11 "B.Adhes" user "B.Adhesive")
		(13 "F.Paste" user "Package Geometry/Pastemask Top")
		(15 "B.Paste" user "Package Geometry/Pastemask Bottom")
		(5 "F.SilkS" user "Ref Des/Silkscreen Top")
		(7 "B.SilkS" user "Ref Des/Silkscreen Bottom")
		(1 "F.Mask" user "Board Geometry/Soldermask Top")
		(3 "B.Mask" user "Board Geometry/Soldermask Bottom")
		(17 "Dwgs.User" user "User.Drawings")
		(19 "Cmts.User" user "User.Comments")
		(21 "Eco1.User" user "User.Eco1")
		(23 "Eco2.User" user "User.Eco2")
		(25 "Edge.Cuts" user "Board Geometry/Outline")
		(27 "Margin" user)
		(31 "F.CrtYd" user "Package Geometry/Place Bound Top")
		(29 "B.CrtYd" user "Package Geometry/Place Bound Bottom")
		(35 "F.Fab" user "Ref Des/Assembly Top")
		(33 "B.Fab" user "Ref Des/Assembly Bottom")
	)
	(footprint ""
		(layer "F.Cu")
		(at 205.232 -129.032 180)
		(property "Reference" "R496"
			(at 0 0 180)
			(layer "F.SilkS")
			(hide yes)
			(effects
				(font
					(size 1.27 1.27)
				)
			)
		)
		(property "Value" ""
			(at 0 0 180)
			(layer "F.Fab")
			(effects
				(font
					(size 1.27 1.27)
				)
			)
		)
		(duplicate_pad_numbers_are_jumpers no)
		(fp_line
			(start 0.7874 0.4064)
			(end -0.7874 0.4064)
			(stroke
				(width 0.1524)
				(type default)
			)
			(layer "F.SilkS")
		)
		(fp_line
			(start 0.7874 -0.4064)
			(end 0.7874 0.4064)
			(stroke
				(width 0.1524)
				(type default)
			)
			(layer "F.SilkS")
		)
		(fp_line
			(start -0.7874 0.4064)
			(end -0.7874 -0.4064)
			(stroke
				(width 0.1524)
				(type default)
			)
			(layer "F.SilkS")
		)
		(fp_line
			(start -0.7874 -0.4064)
			(end 0.7874 -0.4064)
			(stroke
				(width 0.1524)
				(type default)
			)
			(layer "F.SilkS")
		)
		(fp_line
			(start 0.67945 0.3048)
			(end 0.120396 0.3048)
			(stroke
				(width 0.1)
				(type default)
			)
			(layer "F.Fab")
		)
		(fp_line
			(start 0.67945 -0.3048)
			(end 0.67945 0.3048)
			(stroke
				(width 0.1)
				(type default)
			)
			(layer "F.Fab")
		)
		(fp_line
			(start 0.12065 -0.2794)
			(end 0.12065 -0.3048)
			(stroke
				(width 0.1)
				(type default)
			)
			(layer "F.Fab")
		)
		(fp_line
			(start 0.12065 -0.3048)
			(end 0.67945 -0.3048)
			(stroke
				(width 0.1)
				(type default)
			)
			(layer "F.Fab")
		)
		(fp_line
			(start 0.120396 0.3048)
			(end 0.120396 0.2794)
			(stroke
				(width 0.1)
				(type default)
			)
			(layer "F.Fab")
		)
		(fp_line
			(start 0.120396 0.2794)
			(end -0.12065 0.2794)
			(stroke
				(width 0.1)
				(type default)
			)
			(layer "F.Fab")
		)
		(fp_line
			(start -0.12065 0.3048)
			(end -0.67945 0.3048)
			(stroke
				(width 0.1)
				(type default)
			)
			(layer "F.Fab")
		)
		(fp_line
			(start -0.12065 0.2794)
			(end -0.12065 0.3048)
			(stroke
				(width 0.1)
				(type default)
			)
			(layer "F.Fab")
		)
		(fp_line
			(start -0.12065 -0.2794)
			(end 0.12065 -0.2794)
			(stroke
				(width 0.1)
				(type default)
			)
			(layer "F.Fab")
		)
		(fp_line
			(start -0.12065 -0.305054)
			(end -0.12065 -0.2794)
			(stroke
				(width 0.1)
				(type default)
			)
			(layer "F.Fab")
		)
		(fp_line
			(start -0.67945 0.3048)
			(end -0.67945 -0.305054)
			(stroke
				(width 0.1)
				(type default)
			)
			(layer "F.Fab")
		)
		(fp_line
			(start -0.67945 -0.305054)
			(end -0.12065 -0.305054)
			(stroke
				(width 0.1)
				(type default)
			)
			(layer "F.Fab")
		)
		(pad "1" smd circle
			(at -0.40005 0 180)
			(size 0 0)
			(layers "F.Cu" "F.Mask" "F.Paste")
			(net "P3V3_AUX")
		)
		(pad "2" smd circle
			(at 0.40005 0 180)
			(size 0 0)
			(layers "F.Cu" "F.Mask" "F.Paste")
			(net "SW_P3V3_EN")
		)
	)
	(footprint ""
		(layer "F.Cu")
		(at 137.033762 -151.616664 -90)
		(property "Reference" "PR336"
			(at 0 0 270)
			(layer "F.SilkS")
			(hide yes)
			(effects
				(font
					(size 1.27 1.27)
				)
			)
		)
		(property "Value" ""
			(at 0 0 270)
			(layer "F.Fab")
			(effects
				(font
					(size 1.27 1.27)
				)
			)
		)
		(duplicate_pad_numbers_are_jumpers no)
		(fp_line
			(start -0.7874 0.4064)
			(end -0.7874 -0.4064)
			(stroke
				(width 0.1524)
				(type default)
			)
			(layer "F.SilkS")
		)
		(fp_line
			(start 0.7874 0.4064)
			(end -0.7874 0.4064)
			(stroke
				(width 0.1524)
				(type default)
			)
			(layer "F.SilkS")
		)
		(fp_line
			(start -0.7874 -0.4064)
			(end 0.7874 -0.4064)
			(stroke
				(width 0.1524)
				(type default)
			)
			(layer "F.SilkS")
		)
		(fp_line
			(start 0.7874 -0.4064)
			(end 0.7874 0.4064)
			(stroke
				(width 0.1524)
				(type default)
			)
			(layer "F.SilkS")
		)
		(fp_line
			(start -0.67945 0.3048)
			(end -0.67945 -0.305054)
			(stroke
				(width 0.1)
				(type default)
			)
			(layer "F.Fab")
		)
		(fp_line
			(start -0.12065 0.3048)
			(end -0.67945 0.3048)
			(stroke
				(width 0.1)
				(type default)
			)
			(layer "F.Fab")
		)
		(fp_line
			(start 0.120396 0.3048)
			(end 0.120396 0.2794)
			(stroke
				(width 0.1)
				(type default)
			)
			(layer "F.Fab")
		)
		(fp_line
			(start 0.67945 0.3048)
			(end 0.120396 0.3048)
			(stroke
				(width 0.1)
				(type default)
			)
			(layer "F.Fab")
		)
		(fp_line
			(start -0.12065 0.2794)
			(end -0.12065 0.3048)
			(stroke
				(width 0.1)
				(type default)
			)
			(layer "F.Fab")
		)
		(fp_line
			(start 0.120396 0.2794)
			(end -0.12065 0.2794)
			(stroke
				(width 0.1)
				(type default)
			)
			(layer "F.Fab")
		)
		(fp_line
			(start -0.12065 -0.2794)
			(end 0.12065 -0.2794)
			(stroke
				(width 0.1)
				(type default)
			)
			(layer "F.Fab")
		)
		(fp_line
			(start 0.12065 -0.2794)
			(end 0.12065 -0.3048)
			(stroke
				(width 0.1)
				(type default)
			)
			(layer "F.Fab")
		)
		(fp_line
			(start 0.12065 -0.3048)
			(end 0.67945 -0.3048)
			(stroke
				(width 0.1)
				(type default)
			)
			(layer "F.Fab")
		)
		(fp_line
			(start 0.67945 -0.3048)
			(end 0.67945 0.3048)
			(stroke
				(width 0.1)
				(type default)
			)
			(layer "F.Fab")
		)
		(fp_line
			(start -0.67945 -0.305054)
			(end -0.12065 -0.305054)
			(stroke
				(width 0.1)
				(type default)
			)
			(layer "F.Fab")
		)
		(fp_line
			(start -0.12065 -0.305054)
			(end -0.12065 -0.2794)
			(stroke
				(width 0.1)
				(type default)
			)
			(layer "F.Fab")
		)
		(pad "1" smd circle
			(at -0.40005 0 270)
			(size 0 0)
			(layers "F.Cu" "F.Mask" "F.Paste")
			(net "PVDDCR_CPU0_P1_PVCC")
		)
		(pad "2" smd circle
			(at 0.40005 0 270)
			(size 0 0)
			(layers "F.Cu" "F.Mask" "F.Paste")
			(net "P3V3_AUX")
		)
	)
	(footprint ""
		(layer "F.Cu")
		(at 130.49758 -26.99258 -90)
		(property "Reference" "R6192"
			(at 0 0 270)
			(layer "F.SilkS")
			(hide yes)
			(effects
				(font
					(size 1.27 1.27)
				)
			)
		)
		(property "Value" ""
			(at 0 0 270)
			(layer "F.Fab")
			(effects
				(font
					(size 1.27 1.27)
				)
			)
		)
		(duplicate_pad_numbers_are_jumpers no)
		(fp_line
			(start -0.32512 0.175006)
			(end -0.32512 -0.175006)
			(stroke
				(width 0.1)
				(type default)
			)
			(layer "F.Fab")
		)
		(fp_line
			(start 0.32512 0.175006)
			(end -0.32512 0.175006)
			(stroke
				(width 0.1)
				(type default)
			)
			(layer "F.Fab")
		)
		(fp_line
			(start -0.32512 -0.175006)
			(end 0.32512 -0.175006)
			(stroke
				(width 0.1)
				(type default)
			)
			(layer "F.Fab")
		)
		(fp_line
			(start 0.32512 -0.175006)
			(end 0.32512 0.175006)
			(stroke
				(width 0.1)
				(type default)
			)
			(layer "F.Fab")
		)
		(pad "1" smd rect
			(at -0.2667 0 270)
			(size 0.3048 0.381)
			(layers "F.Cu" "F.Mask" "F.Paste")
			(net "USB2_CPU0_P0_DP")
		)
		(pad "2" smd rect
			(at 0.2667 0 90)
			(size 0.3048 0.381)
			(layers "F.Cu" "F.Mask" "F.Paste")
			(net "USB2_CPU0_P0_R2_DP")
		)
	)
)
